# Lightning  M.2_Stackup.xlsx — 工作表2 (pcb-stackup)
|  |  |  |  |  | Version |  |  |  |  |  |  |  |  |  |  |  |  |  |  |
| Board Number: |  | 15750-1 |  |  | 02 |  |  |  |  |  |  |  |  |  |  |  |  |  |  |
| Project name: |  | Lightning_PMC |  |  |  |  |  |  |  |  |  |  |  |  |  |  |  |  |  |
| Model Name: |  | M.2 Card |  |  |  |  |  |  |  |  |  |  |  |  |  |  |  |  |  |
| Layer Count: |  | 8 Layer |  |  |  |  |  |  |  |  |  |  |  |  |  |  |  |  |  |
| Date: |  | 42691 |  |  |  |  |  |  |  |  |  |  |  |  |  |  |  |  |  |
| Material: |  | TU863+VLP / NPG171+VLP |  |  |  |  |  |  | Single Ended Type(mil) |  |  |  |  | Differential Type(mil) |  |  |  |  |  |
| Gold Finger (Y/N) |  | N |  |  |  |  |  | Imp | 50 |  |  |  | Imp | 85 |  |  |  |  |  |
| Customer: |  | <name> |  |  |  |  |  | Variation | Inner/Outer+/-5ohm |  |  |  | Variation | Inner/Outer+/-10% |  |  |  |  |  |
| EE engineer |  | <name> |  |  |  |  |  | Bus | MISC./I2C |  |  |  | Bus | PCIe / CLK |  |  |  |  |  |
| SI Engineer |  | <name> |  |  |  |  |  |  |  |  |  |  |  |  |  |  |  |  |  |
|  |  |  |  |  |  |  |  | Type | SE |  |  |  | Type | DP |  |  |  |  |  |
| Layer |  |  | Thickness | Glass/Copper Style | Er |  | Df(1G) | Layers | 1,3,6,8 |  |  |  | Layers | 1,3,6,8 |  |  |  |  |  |
|  |  | Cu oz | Wiwynn |  | Wiwynn |  |  |  | Wiwynn |  |  |  |  | Wiwynn |  |  |  |  |  |
|  | Mask |  | 0.5 |  | 3.4 |  | 2.5000000000000001E-2 |  | Width | Imp | Width | Imp |  | Width | Space | Imp | Width | Space | Imp |
| Top | Signal | 0.5 oz+plating | 2.1 |  |  |  |  | S1 | 4.75(L2) | 50.46 |  |  | S1 | 5.38(L2) | 6.2 | 85.36 |  |  |  |
|  | Prepreg |  | 3 |  | 3.9 |  | 8.9999999999999993E-3 |  |  |  |  |  |  |  |  |  |  |  |  |
| L2 | GND | 1 oz | 1.3 |  |  |  |  | P2 | reference layer |  |  |  | P2 | reference layer |  |  |  |  |  |
|  | Core |  | 4 |  | 3.9 |  | 8.9999999999999993E-3 |  |  |  |  |  |  |  |  |  |  |  |  |
| L3 | Signal | 1 oz | 1.3 |  |  |  |  | S3 | 4.75(L2/L4) | 49.57 |  |  | S3 | 5.25(L2/L4) | 7.5 | 85.23 |  |  |  |
|  | Prepreg |  | 16 |  | 4.5 |  | 8.9999999999999993E-3 |  |  |  |  |  |  |  |  |  |  |  |  |
| L4 | GND | 1 oz | 1.3 |  |  |  |  | P4 | reference layer |  |  |  | P4 | reference layer |  |  |  |  |  |
|  | Core |  | 4 |  | 3.9 |  | 8.9999999999999993E-3 |  |  |  |  |  |  |  |  |  |  |  |  |
| L5 | GND | 1 oz | 1.3 |  |  |  |  | P5 | reference layer |  |  |  | P5 | reference layer |  |  |  |  |  |
|  | Prepreg |  | 16 |  | 4.5 |  | 8.9999999999999993E-3 |  |  |  |  |  |  |  |  |  |  |  |  |
| L6 | Signal | 1 oz | 1.3 |  |  |  |  | S6 | 4.75(L5/L7) | 49.57 |  |  | S6 | 5.25(L5/L7) | 7.5 | 85.23 |  |  |  |
|  | Core |  | 4 |  | 3.9 | 0 | 8.9999999999999993E-3 |  |  |  |  |  |  |  |  |  |  |  |  |
| L7 | GND | 1 oz | 1.3 |  |  |  |  | P7 | reference layer |  |  |  | P7 | reference layer |  |  |  |  |  |
|  | Prepreg |  | 3 |  | 3.9 | 0 | 8.9999999999999993E-3 |  |  |  |  |  |  |  |  |  |  |  |  |
| Bottom | Signal | 0.5 oz+plating | 2.1 |  |  |  |  | S8 | 4.75(L7) | 50.46 |  |  | S8 | 5.38(L7) | 6.2 | 85.36 |  |  |  |
|  | Mask |  | 0.5 |  | 3.4 | 0 | 2.5000000000000001E-2 |  |  |  |  |  |  |  |  |  |  |  |  |
| Thickness requirement: 1.6 +/- 10% mm |  | mil | 62.999999999999993 |  |  |  |  |  |  |  |  |  |  |  |  |  |  |  |  |
|  |  | mm | 1.6002032004064006 |  |  |  |  |  |  |  |  |  |  |  |  |  |  |  |  |
| Note: | 1. Unit is mil |  |  |  |  |  |  |  |  |  |  |  |  |  |  |  |  |  |  |
|  | 2. The total thickness includes trace and solder mask |  |  |  |  |  |  |  |  |  |  |  |  |  |  |  |  |  |  |
|  | 3. Min hole copper thickness is 1.0 mil |  |  |  |  |  |  |  |  |  |  |  |  |  |  |  |  |  |  |
|  | 4. Min surface copper thickness 1.5 mil |  |  |  |  |  |  |  |  |  |  |  |  |  |  |  |  |  |  |
|  | 5. Impedance Cpk requirement: >=1.33 (Report should be provided) |  |  |  |  |  |  |  |  |  |  |  |  |  |  |  |  |  |  |
|  | 6. PCB supplier should design SET2DIL coupon and provide measurement results meeting following criteria: |  |  |  |  |  |  |  |  |  |  |  |  |  |  |  |  |  |  |
|  | 。  -0.65dB/inch at 4GHz for stripline routing |  |  |  |  |  |  |  |  |  |  |  |  |  |  |  |  |  |  |
|  | 。  -0.69dB/inch at 4GHz for microstrip routing |  |  |  |  |  |  |  |  |  |  |  |  |  |  |  |  |  |  |
